#ISCELL
  logical_power cad_note *
  *
#ISCELL
  mstr_misc dns *
  *
#ISCELL
  pure_quanta quanta_title_block_c *
  *
#CELL
  pure_quanta q_cap *
  page54_i100
#ISCELL
  logical_power universal_gnd *
  page54_i101
#CELL
  pure_quanta q_res *
  page54_i102
#ISCELL
  standard offpage *
  page54_i103
#CELL
  pure_quanta q_cap *
  page54_i104
#CELL
  pure_quanta q_cap *
  page54_i105
#CELL
  pure_quanta q_cap *
  page54_i106
#CELL
  pure_quanta q_cap *
  page54_i107
#CELL
  pure_quanta q_res *
  page54_i108
#ISCELL
  standard offpage *
  page54_i110
#ISCELL
  logical_power universal_gnd *
  page54_i111
#CELL
  pure_quanta q_cap *
  page54_i112
#ISCELL
  logical_power universal_gnd *
  page54_i114
#CELL
  pure_quanta mc74vhc1g32dtt1g *
  page54_i116
#ISCELL
  standard offpage *
  page54_i117
#CELL
  pure_quanta q_cap *
  page54_i130
#ISCELL
  logical_power universal_gnd *
  page54_i131
#CELL
  pure_quanta q_res *
  page54_i132
#ISCELL
  standard offpage *
  page54_i136
#CELL
  pure_quanta q_res *
  page54_i137
#ISCELL
  standard offpage *
  page54_i138
#CELL
  pure_quanta q_res *
  page54_i139
#ISCELL
  standard offpage *
  page54_i140
#ISCELL
  logical_power universal_power *
  page54_i141
#ISCELL
  logical_power universal_gnd *
  page54_i54
#ISCELL
  logical_power universal_gnd *
  page54_i58
#ISCELL
  logical_power vccaux15 *
  page54_i60
#ISCELL
  logical_power universal_gnd *
  page54_i61
#ISCELL
  logical_power universal_gnd *
  page54_i62
#ISCELL
  logical_power vccaux15 *
  page54_i64
#ISCELL
  logical_power vccaux15 *
  page54_i67
#ISCELL
  logical_power vccaux15 *
  page54_i89
#ISCELL
  standard offpage *
  page54_i90
#CELL
  pure_quanta rt9059gqw *
  page54_i96
#CELL
  pure_quanta q_res *
  page54_i97
#CELL
  pure_quanta q_res *
  page54_i98
#CELL
  pure_quanta q_res *
  page54_i99
